# TIMECARD (Time Appliance Project (Time Card)) — schematic netlist excerpt (pin names and nets, part order shuffled) for the footprints in the layout excerpt that follows; sources: Cadence DE-HDL packaged netlist, KiCad conversion of R4006-B0001-02_R01.brd

R244  RESISTOR  0OHM -  pkg SMC_0402R_H016  page 29 : \1\ = XP3R3V_PG ; \2\ = UNNAMED_523_CAPACITOR_I7_1
R115  RESISTOR  4.7KOHM 1%  pkg SMC_0402R_H016  page 22 : \1\ = XP3R3V_GPS ; \2\ = GPS_RST_N

(kicad_pcb
	(version 20260206)
	(generator "pcbnew")
	(generator_version "10.0")
	(general
		(thickness 1.6)
		(legacy_teardrops no)
	)
	(paper "A4")
	(title_block
		(title "timecard-production-celestica-r4006 — R4006-B0001-02_R01.brd")
		(comment 1 "Time Appliance Project (Time Card) / footprints 724-725 of 1113")
	)
	(layers
		(0 "F.Cu" signal "TOP")
		(4 "In1.Cu" signal "L02_GND1")
		(6 "In2.Cu" signal "L03_SIG1")
		(8 "In3.Cu" signal "L04_GND2")
		(10 "In4.Cu" signal "L05_VCC1")
		(12 "In5.Cu" signal "L06_VCC2")
		(14 "In6.Cu" signal "L07_GND3")
		(16 "In7.Cu" signal "L08_SIG2")
		(18 "In8.Cu" signal "L09_GND4")
		(2 "B.Cu" signal "BOTTOM")
		(9 "F.Adhes" user "F.Adhesive")
		(11 "B.Adhes" user "B.Adhesive")
		(13 "F.Paste" user "Package Geometry/Pastemask Top")
		(15 "B.Paste" user "Package Geometry/Pastemask Bottom")
		(5 "F.SilkS" user "Ref Des/Silkscreen Top")
		(7 "B.SilkS" user "Ref Des/Silkscreen Bottom")
		(1 "F.Mask" user "Board Geometry/Soldermask Top")
		(3 "B.Mask" user "Board Geometry/Soldermask Bottom")
		(17 "Dwgs.User" user "User.Drawings")
		(19 "Cmts.User" user "User.Comments")
		(21 "Eco1.User" user "User.Eco1")
		(23 "Eco2.User" user "User.Eco2")
		(25 "Edge.Cuts" user "Board Geometry/Outline")
		(27 "Margin" user)
		(31 "F.CrtYd" user "Package Geometry/Place Bound Top")
		(29 "B.CrtYd" user "Package Geometry/Place Bound Bottom")
		(35 "F.Fab" user "Ref Des/Assembly Top")
		(33 "B.Fab" user "Ref Des/Assembly Bottom")
	)
	(footprint ""
		(layer "B.Cu")
		(at 120.8278 -90.1954)
		(property "Reference" "R115"
			(at -0.4318 -1.20523 0)
			(unlocked yes)
			(layer "B.SilkS")
			(effects
				(font
					(size 0.7874 0.5842)
					(thickness 0.1524)
				)
				(justify mirror)
			)
		)
		(property "Value" "VAL*"
			(at -0.02032 2.13233 0)
			(unlocked yes)
			(layer "B.Fab")
			(hide yes)
			(effects
				(font
					(size 0.7874 0.5842)
					(thickness 0.1524)
				)
				(justify mirror)
			)
		)
		(property "Device Type" "RESISTOR-G155-14701-01,4.7KOHMA"
			(at -0.008382 1.210564 0)
			(unlocked yes)
			(layer "B.Fab")
			(hide yes)
			(effects
				(font
					(size 0.7874 0.5842)
					(thickness 0.1524)
				)
				(justify mirror)
			)
		)
		(property "User Part Number" "PARTNUM*"
			(at -0.02032 4.024884 0)
			(unlocked yes)
			(layer "Cmts.User")
			(hide yes)
			(effects
				(font
					(size 0.7874 0.5842)
					(thickness 0.1524)
				)
				(justify mirror)
			)
		)
		(property "Tolerance" "TOL*"
			(at -0.044704 3.05435 0)
			(unlocked yes)
			(layer "Cmts.User")
			(hide yes)
			(effects
				(font
					(size 0.7874 0.5842)
					(thickness 0.1524)
				)
				(justify mirror)
			)
		)
		(duplicate_pad_numbers_are_jumpers no)
		(fp_line
			(start -1.143 -0.5588)
			(end 1.143 -0.5588)
			(stroke
				(width 0.1)
				(type default)
			)
			(layer "B.SilkS")
		)
		(fp_line
			(start -1.143 0.5588)
			(end -1.143 -0.5588)
			(stroke
				(width 0.1)
				(type default)
			)
			(layer "B.SilkS")
		)
		(fp_line
			(start 1.143 -0.5588)
			(end 1.143 0.5588)
			(stroke
				(width 0.1)
				(type default)
			)
			(layer "B.SilkS")
		)
		(fp_line
			(start 1.143 0.5588)
			(end -1.143 0.5588)
			(stroke
				(width 0.1)
				(type default)
			)
			(layer "B.SilkS")
		)
		(fp_rect
			(start 1.143 -0.5588)
			(end -1.143 0.5588)
			(stroke
				(width 0)
				(type default)
			)
			(fill no)
			(layer "B.CrtYd")
		)
		(fp_line
			(start -0.508 -0.3048)
			(end 0.508 -0.3048)
			(stroke
				(width 0.1)
				(type default)
			)
			(layer "B.Fab")
		)
		(fp_line
			(start -0.508 0.3048)
			(end -0.508 -0.3048)
			(stroke
				(width 0.1)
				(type default)
			)
			(layer "B.Fab")
		)
		(fp_line
			(start 0.508 -0.3048)
			(end 0.508 0.3048)
			(stroke
				(width 0.1)
				(type default)
			)
			(layer "B.Fab")
		)
		(fp_line
			(start 0.508 0.3048)
			(end -0.508 0.3048)
			(stroke
				(width 0.1)
				(type default)
			)
			(layer "B.Fab")
		)
		(pad "1" smd rect
			(at 0.5334 0 180)
			(size 0.7112 0.6096)
			(layers "B.Cu" "B.Mask" "B.Paste")
			(net "XP3R3V_GPS")
		)
		(pad "2" smd rect
			(at -0.5334 0 180)
			(size 0.7112 0.6096)
			(layers "B.Cu" "B.Mask" "B.Paste")
			(net "GPS_RST_N")
		)
		(zone
			(layer "B.Cu")
			(hatch none 0.5)
			(connect_pads
				(clearance 0)
			)
			(min_thickness 0.25)
			(keepout
				(tracks allowed)
				(vias not_allowed)
				(pads allowed)
				(copperpour not_allowed)
				(footprints allowed)
			)
			(placement
				(enabled no)
				(sheetname "")
			)
			(fill
				(thermal_gap 0.5)
				(thermal_bridge_width 0.5)
				(island_removal_mode 0)
			)
			(polygon
				(pts
					(xy 120.904 -90.5002) (xy 120.7516 -90.5002) (xy 120.7516 -89.8906) (xy 120.904 -89.8906)
				)
			)
		)
	)
	(footprint ""
		(layer "B.Cu")
		(at 139.954 -59.563 90)
		(property "Reference" "R244"
			(at 3.175 -0.16637 270)
			(unlocked yes)
			(layer "B.SilkS")
			(effects
				(font
					(size 0.7874 0.5842)
					(thickness 0.1524)
				)
				(justify mirror)
			)
		)
		(property "Value" "VAL*"
			(at -0.02032 2.13233 90)
			(unlocked yes)
			(layer "B.Fab")
			(hide yes)
			(effects
				(font
					(size 0.7874 0.5842)
					(thickness 0.1524)
				)
				(justify mirror)
			)
		)
		(property "Device Type" "RESISTOR-G155-100R0-J0,0OHM,-"
			(at -0.008382 1.210564 90)
			(unlocked yes)
			(layer "B.Fab")
			(hide yes)
			(effects
				(font
					(size 0.7874 0.5842)
					(thickness 0.1524)
				)
				(justify mirror)
			)
		)
		(property "User Part Number" "PARTNUM*"
			(at -0.02032 4.024884 90)
			(unlocked yes)
			(layer "Cmts.User")
			(hide yes)
			(effects
				(font
					(size 0.7874 0.5842)
					(thickness 0.1524)
				)
				(justify mirror)
			)
		)
		(property "Tolerance" "TOL*"
			(at -0.044704 3.05435 90)
			(unlocked yes)
			(layer "Cmts.User")
			(hide yes)
			(effects
				(font
					(size 0.7874 0.5842)
					(thickness 0.1524)
				)
				(justify mirror)
			)
		)
		(duplicate_pad_numbers_are_jumpers no)
		(fp_line
			(start 1.143 -0.5588)
			(end 1.143 0.5588)
			(stroke
				(width 0.1)
				(type default)
			)
			(layer "B.SilkS")
		)
		(fp_line
			(start -1.143 -0.5588)
			(end 1.143 -0.5588)
			(stroke
				(width 0.1)
				(type default)
			)
			(layer "B.SilkS")
		)
		(fp_line
			(start 1.143 0.5588)
			(end -1.143 0.5588)
			(stroke
				(width 0.1)
				(type default)
			)
			(layer "B.SilkS")
		)
		(fp_line
			(start -1.143 0.5588)
			(end -1.143 -0.5588)
			(stroke
				(width 0.1)
				(type default)
			)
			(layer "B.SilkS")
		)
		(fp_rect
			(start -1.143 -0.5588)
			(end 1.143 0.5588)
			(stroke
				(width 0)
				(type default)
			)
			(fill no)
			(layer "B.CrtYd")
		)
		(fp_line
			(start 0.508 -0.3048)
			(end 0.508 0.3048)
			(stroke
				(width 0.1)
				(type default)
			)
			(layer "B.Fab")
		)
		(fp_line
			(start -0.508 -0.3048)
			(end 0.508 -0.3048)
			(stroke
				(width 0.1)
				(type default)
			)
			(layer "B.Fab")
		)
		(fp_line
			(start 0.508 0.3048)
			(end -0.508 0.3048)
			(stroke
				(width 0.1)
				(type default)
			)
			(layer "B.Fab")
		)
		(fp_line
			(start -0.508 0.3048)
			(end -0.508 -0.3048)
			(stroke
				(width 0.1)
				(type default)
			)
			(layer "B.Fab")
		)
		(pad "1" smd rect
			(at 0.5334 0 270)
			(size 0.7112 0.6096)
			(layers "B.Cu" "B.Mask" "B.Paste")
			(net "XP3R3V_PG")
		)
		(pad "2" smd rect
			(at -0.5334 0 270)
			(size 0.7112 0.6096)
			(layers "B.Cu" "B.Mask" "B.Paste")
			(net "UNNAMED_523_CAPACITOR_I7_1")
		)
		(zone
			(layer "B.Cu")
			(hatch none 0.5)
			(connect_pads
				(clearance 0)
			)
			(min_thickness 0.25)
			(keepout
				(tracks allowed)
				(vias not_allowed)
				(pads allowed)
				(copperpour not_allowed)
				(footprints allowed)
			)
			(placement
				(enabled no)
				(sheetname "")
			)
			(fill
				(thermal_gap 0.5)
				(thermal_bridge_width 0.5)
				(island_removal_mode 0)
			)
			(polygon
				(pts
					(xy 139.6492 -59.4868) (xy 140.2588 -59.4868) (xy 140.2588 -59.6392) (xy 139.6492 -59.6392)
				)
			)
		)
	)
)
